(kicad_pcb
	(version 20260206)
	(generator "pcbnew")
	(generator_version "10.0")
	(general
		(thickness 1.6)
		(legacy_teardrops no)
	)
	(paper "A4")
	(title_block
		(title "timecard-production-celestica-r4006 — R4006-B0001-02_R01.brd")
		(comment 1 "Time Appliance Project (Time Card) / footprints 18-24 of 1113")
	)
	(layers
		(0 "F.Cu" signal "TOP")
		(4 "In1.Cu" signal "L02_GND1")
		(6 "In2.Cu" signal "L03_SIG1")
		(8 "In3.Cu" signal "L04_GND2")
		(10 "In4.Cu" signal "L05_VCC1")
		(12 "In5.Cu" signal "L06_VCC2")
		(14 "In6.Cu" signal "L07_GND3")
		(16 "In7.Cu" signal "L08_SIG2")
		(18 "In8.Cu" signal "L09_GND4")
		(2 "B.Cu" signal "BOTTOM")
		(9 "F.Adhes" user "F.Adhesive")
		(11 "B.Adhes" user "B.Adhesive")
		(13 "F.Paste" user "Package Geometry/Pastemask Top")
		(15 "B.Paste" user "Package Geometry/Pastemask Bottom")
		(5 "F.SilkS" user "Ref Des/Silkscreen Top")
		(7 "B.SilkS" user "Ref Des/Silkscreen Bottom")
		(1 "F.Mask" user "Board Geometry/Soldermask Top")
		(3 "B.Mask" user "Board Geometry/Soldermask Bottom")
		(17 "Dwgs.User" user "User.Drawings")
		(19 "Cmts.User" user "User.Comments")
		(21 "Eco1.User" user "User.Eco1")
		(23 "Eco2.User" user "User.Eco2")
		(25 "Edge.Cuts" user "Board Geometry/Outline")
		(27 "Margin" user)
		(31 "F.CrtYd" user "Package Geometry/Place Bound Top")
		(29 "B.CrtYd" user "Package Geometry/Place Bound Bottom")
		(35 "F.Fab" user "Ref Des/Assembly Top")
		(33 "B.Fab" user "Ref Des/Assembly Bottom")
	)
	(footprint ""
		(layer "F.Cu")
		(at 150.749 -28.575 180)
		(property "Reference" "R20"
			(at 1.143 1.99263 0)
			(unlocked yes)
			(layer "F.SilkS")
			(effects
				(font
					(size 0.7874 0.5842)
					(thickness 0.1524)
				)
			)
		)
		(property "Value" "VAL*"
			(at 0.02032 2.13233 180)
			(unlocked yes)
			(layer "F.Fab")
			(hide yes)
			(effects
				(font
					(size 0.7874 0.5842)
					(thickness 0.1524)
				)
			)
		)
		(property "Tolerance" "TOL*"
			(at 0.044704 3.05435 180)
			(unlocked yes)
			(layer "Cmts.User")
			(hide yes)
			(effects
				(font
					(size 0.7874 0.5842)
					(thickness 0.1524)
				)
			)
		)
		(property "User Part Number" "PARTNUM*"
			(at 0.02032 4.024884 180)
			(unlocked yes)
			(layer "Cmts.User")
			(hide yes)
			(effects
				(font
					(size 0.7874 0.5842)
					(thickness 0.1524)
				)
			)
		)
		(property "Device Type" "RESISTOR-G155-14701-01,4.7KOHMA"
			(at 0.008382 1.210564 180)
			(unlocked yes)
			(layer "F.Fab")
			(hide yes)
			(effects
				(font
					(size 0.7874 0.5842)
					(thickness 0.1524)
				)
			)
		)
		(duplicate_pad_numbers_are_jumpers no)
		(fp_line
			(start 1.143 0.5588)
			(end 1.143 -0.5588)
			(stroke
				(width 0.1)
				(type default)
			)
			(layer "F.SilkS")
		)
		(fp_line
			(start 1.143 -0.5588)
			(end -1.143 -0.5588)
			(stroke
				(width 0.1)
				(type default)
			)
			(layer "F.SilkS")
		)
		(fp_line
			(start -1.143 0.5588)
			(end 1.143 0.5588)
			(stroke
				(width 0.1)
				(type default)
			)
			(layer "F.SilkS")
		)
		(fp_line
			(start -1.143 -0.5588)
			(end -1.143 0.5588)
			(stroke
				(width 0.1)
				(type default)
			)
			(layer "F.SilkS")
		)
		(fp_rect
			(start 1.143 -0.5588)
			(end -1.143 0.5588)
			(stroke
				(width 0)
				(type default)
			)
			(fill no)
			(layer "F.CrtYd")
		)
		(fp_line
			(start 0.508 0.3048)
			(end 0.508 -0.3048)
			(stroke
				(width 0.1)
				(type default)
			)
			(layer "F.Fab")
		)
		(fp_line
			(start 0.508 -0.3048)
			(end -0.508 -0.3048)
			(stroke
				(width 0.1)
				(type default)
			)
			(layer "F.Fab")
		)
		(fp_line
			(start -0.508 0.3048)
			(end 0.508 0.3048)
			(stroke
				(width 0.1)
				(type default)
			)
			(layer "F.Fab")
		)
		(fp_line
			(start -0.508 -0.3048)
			(end -0.508 0.3048)
			(stroke
				(width 0.1)
				(type default)
			)
			(layer "F.Fab")
		)
		(pad "1" smd rect
			(at -0.5334 0 180)
			(size 0.7112 0.6096)
			(layers "F.Cu" "F.Mask" "F.Paste")
			(net "XP3R3V_FPGA")
		)
		(pad "2" smd rect
			(at 0.5334 0 180)
			(size 0.7112 0.6096)
			(layers "F.Cu" "F.Mask" "F.Paste")
			(net "LM75B_I2C_SDA")
		)
		(zone
			(layer "F.Cu")
			(hatch none 0.5)
			(connect_pads
				(clearance 0)
			)
			(min_thickness 0.25)
			(keepout
				(tracks allowed)
				(vias not_allowed)
				(pads allowed)
				(copperpour not_allowed)
				(footprints allowed)
			)
			(placement
				(enabled no)
				(sheetname "")
			)
			(fill
				(thermal_gap 0.5)
				(thermal_bridge_width 0.5)
				(island_removal_mode 0)
			)
			(polygon
				(pts
					(xy 150.6728 -28.2702) (xy 150.8252 -28.2702) (xy 150.8252 -28.8798) (xy 150.6728 -28.8798)
				)
			)
		)
	)
	(footprint ""
		(layer "F.Cu")
		(at 162.56 -27.432 180)
		(property "Reference" "R419"
			(at -2.667 0.72263 0)
			(unlocked yes)
			(layer "F.SilkS")
			(effects
				(font
					(size 0.7874 0.5842)
					(thickness 0.1524)
				)
			)
		)
		(property "Value" "VAL*"
			(at 0.02032 2.13233 180)
			(unlocked yes)
			(layer "F.Fab")
			(hide yes)
			(effects
				(font
					(size 0.7874 0.5842)
					(thickness 0.1524)
				)
			)
		)
		(property "Tolerance" "TOL*"
			(at 0.044704 3.05435 180)
			(unlocked yes)
			(layer "Cmts.User")
			(hide yes)
			(effects
				(font
					(size 0.7874 0.5842)
					(thickness 0.1524)
				)
			)
		)
		(property "User Part Number" "PARTNUM*"
			(at 0.02032 4.024884 180)
			(unlocked yes)
			(layer "Cmts.User")
			(hide yes)
			(effects
				(font
					(size 0.7874 0.5842)
					(thickness 0.1524)
				)
			)
		)
		(property "Device Type" "RESISTOR-G155-14701-01,4.7KOHMA"
			(at 0.008382 1.210564 180)
			(unlocked yes)
			(layer "F.Fab")
			(hide yes)
			(effects
				(font
					(size 0.7874 0.5842)
					(thickness 0.1524)
				)
			)
		)
		(duplicate_pad_numbers_are_jumpers no)
		(fp_line
			(start 1.143 0.5588)
			(end 1.143 -0.5588)
			(stroke
				(width 0.1)
				(type default)
			)
			(layer "F.SilkS")
		)
		(fp_line
			(start 1.143 -0.5588)
			(end -1.143 -0.5588)
			(stroke
				(width 0.1)
				(type default)
			)
			(layer "F.SilkS")
		)
		(fp_line
			(start -1.143 0.5588)
			(end 1.143 0.5588)
			(stroke
				(width 0.1)
				(type default)
			)
			(layer "F.SilkS")
		)
		(fp_line
			(start -1.143 -0.5588)
			(end -1.143 0.5588)
			(stroke
				(width 0.1)
				(type default)
			)
			(layer "F.SilkS")
		)
		(fp_rect
			(start 1.143 -0.5588)
			(end -1.143 0.5588)
			(stroke
				(width 0)
				(type default)
			)
			(fill no)
			(layer "F.CrtYd")
		)
		(fp_line
			(start 0.508 0.3048)
			(end 0.508 -0.3048)
			(stroke
				(width 0.1)
				(type default)
			)
			(layer "F.Fab")
		)
		(fp_line
			(start 0.508 -0.3048)
			(end -0.508 -0.3048)
			(stroke
				(width 0.1)
				(type default)
			)
			(layer "F.Fab")
		)
		(fp_line
			(start -0.508 0.3048)
			(end 0.508 0.3048)
			(stroke
				(width 0.1)
				(type default)
			)
			(layer "F.Fab")
		)
		(fp_line
			(start -0.508 -0.3048)
			(end -0.508 0.3048)
			(stroke
				(width 0.1)
				(type default)
			)
			(layer "F.Fab")
		)
		(pad "1" smd rect
			(at -0.5334 0 180)
			(size 0.7112 0.6096)
			(layers "F.Cu" "F.Mask" "F.Paste")
			(net "XP3R3V_FPGA")
		)
		(pad "2" smd rect
			(at 0.5334 0 180)
			(size 0.7112 0.6096)
			(layers "F.Cu" "F.Mask" "F.Paste")
			(net "UNNAMED_6_LM75BDPTSSOP8_I81_A0")
		)
		(zone
			(layer "F.Cu")
			(hatch none 0.5)
			(connect_pads
				(clearance 0)
			)
			(min_thickness 0.25)
			(keepout
				(tracks not_allowed)
				(vias allowed)
				(pads allowed)
				(copperpour not_allowed)
				(footprints allowed)
			)
			(placement
				(enabled no)
				(sheetname "")
			)
			(fill
				(thermal_gap 0.5)
				(thermal_bridge_width 0.5)
				(island_removal_mode 0)
			)
			(polygon
				(pts
					(xy 162.4838 -27.1272) (xy 162.6362 -27.1272) (xy 162.6362 -27.7368) (xy 162.4838 -27.7368)
				)
			)
		)
		(zone
			(layer "F.Cu")
			(hatch none 0.5)
			(connect_pads
				(clearance 0)
			)
			(min_thickness 0.25)
			(keepout
				(tracks allowed)
				(vias not_allowed)
				(pads allowed)
				(copperpour not_allowed)
				(footprints allowed)
			)
			(placement
				(enabled no)
				(sheetname "")
			)
			(fill
				(thermal_gap 0.5)
				(thermal_bridge_width 0.5)
				(island_removal_mode 0)
			)
			(polygon
				(pts
					(xy 162.4838 -27.1272) (xy 162.6362 -27.1272) (xy 162.6362 -27.7368) (xy 162.4838 -27.7368)
				)
			)
		)
	)
	(footprint ""
		(layer "F.Cu")
		(at 133.858 -19.304 180)
		(property "Reference" "R476"
			(at 0.127 5.04063 0)
			(unlocked yes)
			(layer "F.SilkS")
			(effects
				(font
					(size 0.7874 0.5842)
					(thickness 0.1524)
				)
			)
		)
		(property "Value" "VAL*"
			(at 0.02032 2.13233 180)
			(unlocked yes)
			(layer "F.Fab")
			(hide yes)
			(effects
				(font
					(size 0.7874 0.5842)
					(thickness 0.1524)
				)
			)
		)
		(property "Tolerance" "TOL*"
			(at 0.044704 3.05435 180)
			(unlocked yes)
			(layer "Cmts.User")
			(hide yes)
			(effects
				(font
					(size 0.7874 0.5842)
					(thickness 0.1524)
				)
			)
		)
		(property "User Part Number" "PARTNUM*"
			(at 0.02032 4.024884 180)
			(unlocked yes)
			(layer "Cmts.User")
			(hide yes)
			(effects
				(font
					(size 0.7874 0.5842)
					(thickness 0.1524)
				)
			)
		)
		(property "Device Type" "RESISTOR-G155-11003-01,100KOHMA"
			(at 0.008382 1.210564 180)
			(unlocked yes)
			(layer "F.Fab")
			(hide yes)
			(effects
				(font
					(size 0.7874 0.5842)
					(thickness 0.1524)
				)
			)
		)
		(duplicate_pad_numbers_are_jumpers no)
		(fp_line
			(start 1.143 0.5588)
			(end 1.143 -0.5588)
			(stroke
				(width 0.1)
				(type default)
			)
			(layer "F.SilkS")
		)
		(fp_line
			(start 1.143 -0.5588)
			(end -1.143 -0.5588)
			(stroke
				(width 0.1)
				(type default)
			)
			(layer "F.SilkS")
		)
		(fp_line
			(start -1.143 0.5588)
			(end 1.143 0.5588)
			(stroke
				(width 0.1)
				(type default)
			)
			(layer "F.SilkS")
		)
		(fp_line
			(start -1.143 -0.5588)
			(end -1.143 0.5588)
			(stroke
				(width 0.1)
				(type default)
			)
			(layer "F.SilkS")
		)
		(fp_poly
			(pts
				(xy -1.143 0.5588) (xy 1.143 0.5588) (xy 1.143 -0.5588) (xy -1.143 -0.5588)
			)
			(stroke
				(width 0)
				(type default)
			)
			(fill no)
			(layer "F.CrtYd")
		)
		(fp_line
			(start 0.508 0.3048)
			(end 0.508 -0.3048)
			(stroke
				(width 0.1)
				(type default)
			)
			(layer "F.Fab")
		)
		(fp_line
			(start 0.508 -0.3048)
			(end -0.508 -0.3048)
			(stroke
				(width 0.1)
				(type default)
			)
			(layer "F.Fab")
		)
		(fp_line
			(start -0.508 0.3048)
			(end 0.508 0.3048)
			(stroke
				(width 0.1)
				(type default)
			)
			(layer "F.Fab")
		)
		(fp_line
			(start -0.508 -0.3048)
			(end -0.508 0.3048)
			(stroke
				(width 0.1)
				(type default)
			)
			(layer "F.Fab")
		)
		(pad "1" smd rect
			(at -0.5334 0 180)
			(size 0.7112 0.6096)
			(layers "F.Cu" "F.Mask" "F.Paste")
			(net "XP3R3V_FPGA")
		)
		(pad "2" smd rect
			(at 0.5334 0 180)
			(size 0.7112 0.6096)
			(layers "F.Cu" "F.Mask" "F.Paste")
			(net "FPGA_EEPROM_I2C_SDA")
		)
		(zone
			(layer "F.Cu")
			(hatch none 0.5)
			(connect_pads
				(clearance 0)
			)
			(min_thickness 0.25)
			(keepout
				(tracks allowed)
				(vias not_allowed)
				(pads allowed)
				(copperpour not_allowed)
				(footprints allowed)
			)
			(placement
				(enabled no)
				(sheetname "")
			)
			(fill
				(thermal_gap 0.5)
				(thermal_bridge_width 0.5)
				(island_removal_mode 0)
			)
			(polygon
				(pts
					(xy 133.9342 -19.6088) (xy 133.7818 -19.6088) (xy 133.7818 -18.9992) (xy 133.9342 -18.9992)
				)
			)
		)
		(zone
			(layer "F.Cu")
			(hatch none 0.5)
			(connect_pads
				(clearance 0)
			)
			(min_thickness 0.25)
			(keepout
				(tracks not_allowed)
				(vias allowed)
				(pads allowed)
				(copperpour not_allowed)
				(footprints allowed)
			)
			(placement
				(enabled no)
				(sheetname "")
			)
			(fill
				(thermal_gap 0.5)
				(thermal_bridge_width 0.5)
				(island_removal_mode 0)
			)
			(polygon
				(pts
					(xy 133.9342 -19.6088) (xy 133.7818 -19.6088) (xy 133.7818 -18.9992) (xy 133.9342 -18.9992)
				)
			)
		)
	)
	(footprint ""
		(layer "F.Cu")
		(at 146.685 -19.685 -90)
		(property "Reference" "R228"
			(at 3.21437 -2.667 0)
			(unlocked yes)
			(layer "F.SilkS")
			(effects
				(font
					(size 0.7874 0.5842)
					(thickness 0.1524)
				)
			)
		)
		(property "Value" "VAL*"
			(at 0.0508 2.245106 270)
			(unlocked yes)
			(layer "F.Fab")
			(hide yes)
			(effects
				(font
					(size 0.7874 0.5842)
					(thickness 0.1524)
				)
			)
		)
		(property "User Part Number" "PARTNUM*"
			(at 0.0762 4.302506 270)
			(unlocked yes)
			(layer "Cmts.User")
			(hide yes)
			(effects
				(font
					(size 0.7874 0.5842)
					(thickness 0.1524)
				)
			)
		)
		(property "Device Type" "RESISTOR-G152-00055-01,1.13KOHA"
			(at 0.0762 1.254506 270)
			(unlocked yes)
			(layer "F.Fab")
			(hide yes)
			(effects
				(font
					(size 0.7874 0.5842)
					(thickness 0.1524)
				)
			)
		)
		(property "Tolerance" "TOL*"
			(at 0.0508 3.261106 270)
			(unlocked yes)
			(layer "Cmts.User")
			(hide yes)
			(effects
				(font
					(size 0.7874 0.5842)
					(thickness 0.1524)
				)
			)
		)
		(duplicate_pad_numbers_are_jumpers no)
		(fp_line
			(start -1.143 0.5588)
			(end 1.143 0.5588)
			(stroke
				(width 0.1)
				(type default)
			)
			(layer "F.SilkS")
		)
		(fp_line
			(start 1.143 0.5588)
			(end 1.143 -0.5588)
			(stroke
				(width 0.1)
				(type default)
			)
			(layer "F.SilkS")
		)
		(fp_line
			(start -1.143 -0.5588)
			(end -1.143 0.5588)
			(stroke
				(width 0.1)
				(type default)
			)
			(layer "F.SilkS")
		)
		(fp_line
			(start 1.143 -0.5588)
			(end -1.143 -0.5588)
			(stroke
				(width 0.1)
				(type default)
			)
			(layer "F.SilkS")
		)
		(fp_rect
			(start -1.143 0.5588)
			(end 1.143 -0.5588)
			(stroke
				(width 0)
				(type default)
			)
			(fill no)
			(layer "F.CrtYd")
		)
		(fp_line
			(start -0.508 0.3048)
			(end 0.508 0.3048)
			(stroke
				(width 0.1)
				(type default)
			)
			(layer "F.Fab")
		)
		(fp_line
			(start 0.508 0.3048)
			(end 0.508 -0.3048)
			(stroke
				(width 0.1)
				(type default)
			)
			(layer "F.Fab")
		)
		(fp_line
			(start -0.508 -0.3048)
			(end -0.508 0.3048)
			(stroke
				(width 0.1)
				(type default)
			)
			(layer "F.Fab")
		)
		(fp_line
			(start 0.508 -0.3048)
			(end -0.508 -0.3048)
			(stroke
				(width 0.1)
				(type default)
			)
			(layer "F.Fab")
		)
		(pad "1" smd rect
			(at -0.5334 0 270)
			(size 0.7112 0.6096)
			(layers "F.Cu" "F.Mask" "F.Paste")
			(net "UNNAMED_515_CAPACITOR_I130_1")
		)
		(pad "2" smd rect
			(at 0.5334 0 270)
			(size 0.7112 0.6096)
			(layers "F.Cu" "F.Mask" "F.Paste")
			(net "UNNAMED_515_CAPACITOR_I128_1")
		)
		(zone
			(layer "F.Cu")
			(hatch none 0.5)
			(connect_pads
				(clearance 0)
			)
			(min_thickness 0.25)
			(keepout
				(tracks allowed)
				(vias not_allowed)
				(pads allowed)
				(copperpour not_allowed)
				(footprints allowed)
			)
			(placement
				(enabled no)
				(sheetname "")
			)
			(fill
				(thermal_gap 0.5)
				(thermal_bridge_width 0.5)
				(island_removal_mode 0)
			)
			(polygon
				(pts
					(xy 146.3802 -19.7612) (xy 146.3802 -19.6088) (xy 146.9898 -19.6088) (xy 146.9898 -19.7612)
				)
			)
		)
	)
	(footprint ""
		(layer "F.Cu")
		(at 22.479 -76.962 90)
		(property "Reference" "TP8"
			(at 0 0 90)
			(layer "F.SilkS")
			(hide yes)
			(effects
				(font
					(size 1.27 1.27)
				)
			)
		)
		(property "Value" ""
			(at 0 0 90)
			(layer "F.Fab")
			(effects
				(font
					(size 1.27 1.27)
				)
			)
		)
		(property "Device Type" "TP_PIONT-TP010CT020B030_PTH-TPA"
			(at -1.341882 0.996696 90)
			(unlocked yes)
			(layer "F.Fab")
			(hide yes)
			(effects
				(font
					(size 0.7874 0.5842)
					(thickness 0.1524)
				)
				(justify left)
			)
		)
		(duplicate_pad_numbers_are_jumpers no)
		(fp_poly
			(pts
				(arc
					(start 0 0.889)
					(mid 0 -0.889)
					(end 0 0.889)
				)
			)
			(stroke
				(width 0)
				(type default)
			)
			(fill no)
			(layer "B.CrtYd")
		)
		(fp_poly
			(pts
				(arc
					(start 0 0.889)
					(mid 0 -0.889)
					(end 0 0.889)
				)
			)
			(stroke
				(width 0)
				(type default)
			)
			(fill no)
			(layer "F.CrtYd")
		)
		(pad "1" thru_hole circle
			(at 0 0 90)
			(size 0.508 0.508)
			(drill 0.254)
			(layers "*.Cu" "*.Mask")
			(remove_unused_layers no)
			(net "UNNAMED_524_FT4232HLREELQFP64_3")
			(clearance 0.1016)
			(padstack
				(mode front_inner_back)
				(layer "Inner"
					(shape circle)
					(size 0.508 0.508)
					(clearance 0.1016)
				)
				(layer "B.Cu"
					(shape circle)
					(size 0.762 0.762)
					(clearance -0.0254)
				)
			)
		)
	)
	(footprint ""
		(layer "F.Cu")
		(at 43.942 -126.111)
		(property "Reference" "SP34"
			(at 0 0 0)
			(layer "F.SilkS")
			(hide yes)
			(effects
				(font
					(size 1.27 1.27)
				)
			)
		)
		(property "Value" ""
			(at 0 0 0)
			(layer "F.Fab")
			(effects
				(font
					(size 1.27 1.27)
				)
			)
		)
		(duplicate_pad_numbers_are_jumpers no)
	)
	(footprint ""
		(layer "F.Cu")
		(at 146.05 -57.023)
		(property "Reference" "R248"
			(at 2.794 2.32537 0)
			(unlocked yes)
			(layer "F.SilkS")
			(effects
				(font
					(size 0.7874 0.5842)
					(thickness 0.1524)
				)
			)
		)
		(property "Value" "VAL*"
			(at 0.02032 2.13233 0)
			(unlocked yes)
			(layer "F.Fab")
			(hide yes)
			(effects
				(font
					(size 0.7874 0.5842)
					(thickness 0.1524)
				)
			)
		)
		(property "Device Type" "RESISTOR-G155-11003-01,100KOHMA"
			(at 0.008382 1.210564 0)
			(unlocked yes)
			(layer "F.Fab")
			(hide yes)
			(effects
				(font
					(size 0.7874 0.5842)
					(thickness 0.1524)
				)
			)
		)
		(property "User Part Number" "PARTNUM*"
			(at 0.02032 4.024884 0)
			(unlocked yes)
			(layer "Cmts.User")
			(hide yes)
			(effects
				(font
					(size 0.7874 0.5842)
					(thickness 0.1524)
				)
			)
		)
		(property "Tolerance" "TOL*"
			(at 0.044704 3.05435 0)
			(unlocked yes)
			(layer "Cmts.User")
			(hide yes)
			(effects
				(font
					(size 0.7874 0.5842)
					(thickness 0.1524)
				)
			)
		)
		(duplicate_pad_numbers_are_jumpers no)
		(fp_line
			(start -1.143 -0.5588)
			(end -1.143 0.5588)
			(stroke
				(width 0.1)
				(type default)
			)
			(layer "F.SilkS")
		)
		(fp_line
			(start -1.143 0.5588)
			(end 1.143 0.5588)
			(stroke
				(width 0.1)
				(type default)
			)
			(layer "F.SilkS")
		)
		(fp_line
			(start 1.143 -0.5588)
			(end -1.143 -0.5588)
			(stroke
				(width 0.1)
				(type default)
			)
			(layer "F.SilkS")
		)
		(fp_line
			(start 1.143 0.5588)
			(end 1.143 -0.5588)
			(stroke
				(width 0.1)
				(type default)
			)
			(layer "F.SilkS")
		)
		(fp_rect
			(start -1.143 0.5588)
			(end 1.143 -0.5588)
			(stroke
				(width 0)
				(type default)
			)
			(fill no)
			(layer "F.CrtYd")
		)
		(fp_line
			(start -0.508 -0.3048)
			(end -0.508 0.3048)
			(stroke
				(width 0.1)
				(type default)
			)
			(layer "F.Fab")
		)
		(fp_line
			(start -0.508 0.3048)
			(end 0.508 0.3048)
			(stroke
				(width 0.1)
				(type default)
			)
			(layer "F.Fab")
		)
		(fp_line
			(start 0.508 -0.3048)
			(end -0.508 -0.3048)
			(stroke
				(width 0.1)
				(type default)
			)
			(layer "F.Fab")
		)
		(fp_line
			(start 0.508 0.3048)
			(end 0.508 -0.3048)
			(stroke
				(width 0.1)
				(type default)
			)
			(layer "F.Fab")
		)
		(pad "1" smd rect
			(at -0.5334 0)
			(size 0.7112 0.6096)
			(layers "F.Cu" "F.Mask" "F.Paste")
			(net "XP1R0V_RT")
		)
		(pad "2" smd rect
			(at 0.5334 0)
			(size 0.7112 0.6096)
			(layers "F.Cu" "F.Mask" "F.Paste")
			(net "XP1R0V_AGND")
		)
		(zone
			(layer "F.Cu")
			(hatch none 0.5)
			(connect_pads
				(clearance 0)
			)
			(min_thickness 0.25)
			(keepout
				(tracks allowed)
				(vias not_allowed)
				(pads allowed)
				(copperpour not_allowed)
				(footprints allowed)
			)
			(placement
				(enabled no)
				(sheetname "")
			)
			(fill
				(thermal_gap 0.5)
				(thermal_bridge_width 0.5)
				(island_removal_mode 0)
			)
			(polygon
				(pts
					(xy 145.9738 -56.7182) (xy 146.1262 -56.7182) (xy 146.1262 -57.3278) (xy 145.9738 -57.3278)
				)
			)
		)
	)
)
